(kicad_pcb
	(version 20260206)
	(generator "pcbnew")
	(generator_version "10.0")
	(general
		(thickness 1.6)
		(legacy_teardrops no)
	)
	(paper "A4")
	(title_block
		(title "04192023_DAF0TMB3IC0_F0TG_MB_C_brd_V02_OCP.brd")
		(comment 1 "Grand Teton / footprints 3896-3904 of 8354")
	)
	(layers
		(0 "F.Cu" signal "TOP")
		(4 "In1.Cu" signal "GND")
		(6 "In2.Cu" signal "IN1")
		(8 "In3.Cu" signal "GND1")
		(10 "In4.Cu" signal "IN2")
		(12 "In5.Cu" signal "GND2")
		(14 "In6.Cu" signal "IN3")
		(16 "In7.Cu" signal "GND3")
		(18 "In8.Cu" signal "VCC")
		(20 "In9.Cu" signal "VCC1")
		(22 "In10.Cu" signal "GND4")
		(24 "In11.Cu" signal "IN4")
		(26 "In12.Cu" signal "GND5")
		(28 "In13.Cu" signal "IN5")
		(30 "In14.Cu" signal "GND6")
		(32 "In15.Cu" signal "IN6")
		(34 "In16.Cu" signal "GND7")
		(2 "B.Cu" signal "BOTTOM")
		(9 "F.Adhes" user "F.Adhesive")
		(11 "B.Adhes" user "B.Adhesive")
		(13 "F.Paste" user "Package Geometry/Pastemask Top")
		(15 "B.Paste" user "Package Geometry/Pastemask Bottom")
		(5 "F.SilkS" user "Ref Des/Silkscreen Top")
		(7 "B.SilkS" user "Ref Des/Silkscreen Bottom")
		(1 "F.Mask" user "Board Geometry/Soldermask Top")
		(3 "B.Mask" user "Board Geometry/Soldermask Bottom")
		(17 "Dwgs.User" user "User.Drawings")
		(19 "Cmts.User" user "User.Comments")
		(21 "Eco1.User" user "User.Eco1")
		(23 "Eco2.User" user "User.Eco2")
		(25 "Edge.Cuts" user "Board Geometry/Outline")
		(27 "Margin" user)
		(31 "F.CrtYd" user "Package Geometry/Place Bound Top")
		(29 "B.CrtYd" user "Package Geometry/Place Bound Bottom")
		(35 "F.Fab" user "Ref Des/Assembly Top")
		(33 "B.Fab" user "Ref Des/Assembly Bottom")
	)
	(footprint ""
		(layer "F.Cu")
		(at 83.445096 -333.24419 90)
		(property "Reference" "PR512"
			(at 0 0 90)
			(layer "F.SilkS")
			(hide yes)
			(effects
				(font
					(size 1.27 1.27)
				)
			)
		)
		(property "Value" ""
			(at 0 0 90)
			(layer "F.Fab")
			(effects
				(font
					(size 1.27 1.27)
				)
			)
		)
		(duplicate_pad_numbers_are_jumpers no)
		(fp_line
			(start 0.7874 -0.4064)
			(end 0.7874 0.4064)
			(stroke
				(width 0.1524)
				(type default)
			)
			(layer "F.SilkS")
		)
		(fp_line
			(start -0.7874 -0.4064)
			(end 0.7874 -0.4064)
			(stroke
				(width 0.1524)
				(type default)
			)
			(layer "F.SilkS")
		)
		(fp_line
			(start 0.7874 0.4064)
			(end -0.7874 0.4064)
			(stroke
				(width 0.1524)
				(type default)
			)
			(layer "F.SilkS")
		)
		(fp_line
			(start -0.7874 0.4064)
			(end -0.7874 -0.4064)
			(stroke
				(width 0.1524)
				(type default)
			)
			(layer "F.SilkS")
		)
		(fp_line
			(start -0.12065 -0.305054)
			(end -0.12065 -0.2794)
			(stroke
				(width 0.1)
				(type default)
			)
			(layer "F.Fab")
		)
		(fp_line
			(start -0.67945 -0.305054)
			(end -0.12065 -0.305054)
			(stroke
				(width 0.1)
				(type default)
			)
			(layer "F.Fab")
		)
		(fp_line
			(start 0.67945 -0.3048)
			(end 0.67945 0.3048)
			(stroke
				(width 0.1)
				(type default)
			)
			(layer "F.Fab")
		)
		(fp_line
			(start 0.12065 -0.3048)
			(end 0.67945 -0.3048)
			(stroke
				(width 0.1)
				(type default)
			)
			(layer "F.Fab")
		)
		(fp_line
			(start 0.12065 -0.2794)
			(end 0.12065 -0.3048)
			(stroke
				(width 0.1)
				(type default)
			)
			(layer "F.Fab")
		)
		(fp_line
			(start -0.12065 -0.2794)
			(end 0.12065 -0.2794)
			(stroke
				(width 0.1)
				(type default)
			)
			(layer "F.Fab")
		)
		(fp_line
			(start 0.120396 0.2794)
			(end -0.12065 0.2794)
			(stroke
				(width 0.1)
				(type default)
			)
			(layer "F.Fab")
		)
		(fp_line
			(start -0.12065 0.2794)
			(end -0.12065 0.3048)
			(stroke
				(width 0.1)
				(type default)
			)
			(layer "F.Fab")
		)
		(fp_line
			(start 0.67945 0.3048)
			(end 0.120396 0.3048)
			(stroke
				(width 0.1)
				(type default)
			)
			(layer "F.Fab")
		)
		(fp_line
			(start 0.120396 0.3048)
			(end 0.120396 0.2794)
			(stroke
				(width 0.1)
				(type default)
			)
			(layer "F.Fab")
		)
		(fp_line
			(start -0.12065 0.3048)
			(end -0.67945 0.3048)
			(stroke
				(width 0.1)
				(type default)
			)
			(layer "F.Fab")
		)
		(fp_line
			(start -0.67945 0.3048)
			(end -0.67945 -0.305054)
			(stroke
				(width 0.1)
				(type default)
			)
			(layer "F.Fab")
		)
		(pad "1" smd circle
			(at -0.40005 0 90)
			(size 0 0)
			(layers "F.Cu" "F.Mask" "F.Paste")
			(net "SW_PVDDCR_CPU1_P1_SW1_RC")
		)
		(pad "2" smd circle
			(at 0.40005 0 90)
			(size 0 0)
			(layers "F.Cu" "F.Mask" "F.Paste")
			(net "GND")
		)
	)
	(footprint ""
		(layer "F.Cu")
		(at 137.971784 -49.595024)
		(property "Reference" "R6216"
			(at 0 0 0)
			(layer "F.SilkS")
			(hide yes)
			(effects
				(font
					(size 1.27 1.27)
				)
			)
		)
		(property "Value" ""
			(at 0 0 0)
			(layer "F.Fab")
			(effects
				(font
					(size 1.27 1.27)
				)
			)
		)
		(duplicate_pad_numbers_are_jumpers no)
		(fp_line
			(start -0.7874 -0.4064)
			(end 0.7874 -0.4064)
			(stroke
				(width 0.1524)
				(type default)
			)
			(layer "F.SilkS")
		)
		(fp_line
			(start -0.7874 0.4064)
			(end -0.7874 -0.4064)
			(stroke
				(width 0.1524)
				(type default)
			)
			(layer "F.SilkS")
		)
		(fp_line
			(start 0.7874 -0.4064)
			(end 0.7874 0.4064)
			(stroke
				(width 0.1524)
				(type default)
			)
			(layer "F.SilkS")
		)
		(fp_line
			(start 0.7874 0.4064)
			(end -0.7874 0.4064)
			(stroke
				(width 0.1524)
				(type default)
			)
			(layer "F.SilkS")
		)
		(fp_line
			(start -0.67945 -0.305054)
			(end -0.12065 -0.305054)
			(stroke
				(width 0.1)
				(type default)
			)
			(layer "F.Fab")
		)
		(fp_line
			(start -0.67945 0.3048)
			(end -0.67945 -0.305054)
			(stroke
				(width 0.1)
				(type default)
			)
			(layer "F.Fab")
		)
		(fp_line
			(start -0.12065 -0.305054)
			(end -0.12065 -0.2794)
			(stroke
				(width 0.1)
				(type default)
			)
			(layer "F.Fab")
		)
		(fp_line
			(start -0.12065 -0.2794)
			(end 0.12065 -0.2794)
			(stroke
				(width 0.1)
				(type default)
			)
			(layer "F.Fab")
		)
		(fp_line
			(start -0.12065 0.2794)
			(end -0.12065 0.3048)
			(stroke
				(width 0.1)
				(type default)
			)
			(layer "F.Fab")
		)
		(fp_line
			(start -0.12065 0.3048)
			(end -0.67945 0.3048)
			(stroke
				(width 0.1)
				(type default)
			)
			(layer "F.Fab")
		)
		(fp_line
			(start 0.120396 0.2794)
			(end -0.12065 0.2794)
			(stroke
				(width 0.1)
				(type default)
			)
			(layer "F.Fab")
		)
		(fp_line
			(start 0.120396 0.3048)
			(end 0.120396 0.2794)
			(stroke
				(width 0.1)
				(type default)
			)
			(layer "F.Fab")
		)
		(fp_line
			(start 0.12065 -0.3048)
			(end 0.67945 -0.3048)
			(stroke
				(width 0.1)
				(type default)
			)
			(layer "F.Fab")
		)
		(fp_line
			(start 0.12065 -0.2794)
			(end 0.12065 -0.3048)
			(stroke
				(width 0.1)
				(type default)
			)
			(layer "F.Fab")
		)
		(fp_line
			(start 0.67945 -0.3048)
			(end 0.67945 0.3048)
			(stroke
				(width 0.1)
				(type default)
			)
			(layer "F.Fab")
		)
		(fp_line
			(start 0.67945 0.3048)
			(end 0.120396 0.3048)
			(stroke
				(width 0.1)
				(type default)
			)
			(layer "F.Fab")
		)
		(pad "1" smd circle
			(at -0.40005 0)
			(size 0 0)
			(layers "F.Cu" "F.Mask" "F.Paste")
			(net "USB_CPU0_HUB1_MODE_SEL0")
		)
		(pad "2" smd circle
			(at 0.40005 0)
			(size 0 0)
			(layers "F.Cu" "F.Mask" "F.Paste")
			(net "GND")
		)
	)
	(footprint ""
		(layer "F.Cu")
		(at 157.933644 -370.57203 -90)
		(property "Reference" "C755"
			(at 0 0 270)
			(layer "F.SilkS")
			(hide yes)
			(effects
				(font
					(size 1.27 1.27)
				)
			)
		)
		(property "Value" ""
			(at 0 0 270)
			(layer "F.Fab")
			(effects
				(font
					(size 1.27 1.27)
				)
			)
		)
		(duplicate_pad_numbers_are_jumpers no)
		(fp_line
			(start -0.299974 0.150114)
			(end -0.299974 -0.150114)
			(stroke
				(width 0.1)
				(type default)
			)
			(layer "F.Fab")
		)
		(fp_line
			(start 0.299974 0.150114)
			(end -0.299974 0.150114)
			(stroke
				(width 0.1)
				(type default)
			)
			(layer "F.Fab")
		)
		(fp_line
			(start -0.299974 -0.150114)
			(end 0.299974 -0.150114)
			(stroke
				(width 0.1)
				(type default)
			)
			(layer "F.Fab")
		)
		(fp_line
			(start 0.299974 -0.150114)
			(end 0.299974 0.150114)
			(stroke
				(width 0.1)
				(type default)
			)
			(layer "F.Fab")
		)
		(pad "1" smd rect
			(at -0.2667 0 270)
			(size 0.3048 0.381)
			(layers "F.Cu" "F.Mask" "F.Paste")
			(net "P5E_CPU1_P2_TX_C_DP<9>")
		)
		(pad "2" smd rect
			(at 0.2667 0 270)
			(size 0.3048 0.381)
			(layers "F.Cu" "F.Mask" "F.Paste")
			(net "P5E_CPU1_P2_TX_DP<9>")
		)
	)
	(footprint ""
		(layer "F.Cu")
		(at 13.537946 -139.26693 -90)
		(property "Reference" "R4078"
			(at 0 0 270)
			(layer "F.SilkS")
			(hide yes)
			(effects
				(font
					(size 1.27 1.27)
				)
			)
		)
		(property "Value" ""
			(at 0 0 270)
			(layer "F.Fab")
			(effects
				(font
					(size 1.27 1.27)
				)
			)
		)
		(duplicate_pad_numbers_are_jumpers no)
		(fp_line
			(start -0.7874 0.4064)
			(end -0.7874 -0.4064)
			(stroke
				(width 0.1524)
				(type default)
			)
			(layer "F.SilkS")
		)
		(fp_line
			(start 0.7874 0.4064)
			(end -0.7874 0.4064)
			(stroke
				(width 0.1524)
				(type default)
			)
			(layer "F.SilkS")
		)
		(fp_line
			(start -0.7874 -0.4064)
			(end 0.7874 -0.4064)
			(stroke
				(width 0.1524)
				(type default)
			)
			(layer "F.SilkS")
		)
		(fp_line
			(start 0.7874 -0.4064)
			(end 0.7874 0.4064)
			(stroke
				(width 0.1524)
				(type default)
			)
			(layer "F.SilkS")
		)
		(fp_line
			(start -0.67945 0.3048)
			(end -0.67945 -0.305054)
			(stroke
				(width 0.1)
				(type default)
			)
			(layer "F.Fab")
		)
		(fp_line
			(start -0.12065 0.3048)
			(end -0.67945 0.3048)
			(stroke
				(width 0.1)
				(type default)
			)
			(layer "F.Fab")
		)
		(fp_line
			(start 0.120396 0.3048)
			(end 0.120396 0.2794)
			(stroke
				(width 0.1)
				(type default)
			)
			(layer "F.Fab")
		)
		(fp_line
			(start 0.67945 0.3048)
			(end 0.120396 0.3048)
			(stroke
				(width 0.1)
				(type default)
			)
			(layer "F.Fab")
		)
		(fp_line
			(start -0.12065 0.2794)
			(end -0.12065 0.3048)
			(stroke
				(width 0.1)
				(type default)
			)
			(layer "F.Fab")
		)
		(fp_line
			(start 0.120396 0.2794)
			(end -0.12065 0.2794)
			(stroke
				(width 0.1)
				(type default)
			)
			(layer "F.Fab")
		)
		(fp_line
			(start -0.12065 -0.2794)
			(end 0.12065 -0.2794)
			(stroke
				(width 0.1)
				(type default)
			)
			(layer "F.Fab")
		)
		(fp_line
			(start 0.12065 -0.2794)
			(end 0.12065 -0.3048)
			(stroke
				(width 0.1)
				(type default)
			)
			(layer "F.Fab")
		)
		(fp_line
			(start 0.12065 -0.3048)
			(end 0.67945 -0.3048)
			(stroke
				(width 0.1)
				(type default)
			)
			(layer "F.Fab")
		)
		(fp_line
			(start 0.67945 -0.3048)
			(end 0.67945 0.3048)
			(stroke
				(width 0.1)
				(type default)
			)
			(layer "F.Fab")
		)
		(fp_line
			(start -0.67945 -0.305054)
			(end -0.12065 -0.305054)
			(stroke
				(width 0.1)
				(type default)
			)
			(layer "F.Fab")
		)
		(fp_line
			(start -0.12065 -0.305054)
			(end -0.12065 -0.2794)
			(stroke
				(width 0.1)
				(type default)
			)
			(layer "F.Fab")
		)
		(pad "1" smd circle
			(at -0.40005 0 270)
			(size 0 0)
			(layers "F.Cu" "F.Mask" "F.Paste")
			(net "P3V3_AUX")
		)
		(pad "2" smd circle
			(at 0.40005 0 270)
			(size 0 0)
			(layers "F.Cu" "F.Mask" "F.Paste")
			(net "FG_SS_EN")
		)
	)
	(footprint ""
		(layer "F.Cu")
		(at 94.817946 -178.29149 180)
		(property "Reference" "PC290_3"
			(at 0 0 180)
			(layer "F.SilkS")
			(hide yes)
			(effects
				(font
					(size 1.27 1.27)
				)
			)
		)
		(property "Value" ""
			(at 0 0 180)
			(layer "F.Fab")
			(effects
				(font
					(size 1.27 1.27)
				)
			)
		)
		(duplicate_pad_numbers_are_jumpers no)
		(fp_line
			(start 0.7874 0.4064)
			(end -0.7874 0.4064)
			(stroke
				(width 0.1524)
				(type default)
			)
			(layer "F.SilkS")
		)
		(fp_line
			(start 0.7874 -0.4064)
			(end 0.7874 0.4064)
			(stroke
				(width 0.1524)
				(type default)
			)
			(layer "F.SilkS")
		)
		(fp_line
			(start -0.7874 0.4064)
			(end -0.7874 -0.4064)
			(stroke
				(width 0.1524)
				(type default)
			)
			(layer "F.SilkS")
		)
		(fp_line
			(start -0.7874 -0.4064)
			(end 0.7874 -0.4064)
			(stroke
				(width 0.1524)
				(type default)
			)
			(layer "F.SilkS")
		)
		(fp_line
			(start 0.67945 0.3048)
			(end 0.120396 0.3048)
			(stroke
				(width 0.1)
				(type default)
			)
			(layer "F.Fab")
		)
		(fp_line
			(start 0.67945 -0.3048)
			(end 0.67945 0.3048)
			(stroke
				(width 0.1)
				(type default)
			)
			(layer "F.Fab")
		)
		(fp_line
			(start 0.12065 -0.2794)
			(end 0.12065 -0.3048)
			(stroke
				(width 0.1)
				(type default)
			)
			(layer "F.Fab")
		)
		(fp_line
			(start 0.12065 -0.3048)
			(end 0.67945 -0.3048)
			(stroke
				(width 0.1)
				(type default)
			)
			(layer "F.Fab")
		)
		(fp_line
			(start 0.120396 0.3048)
			(end 0.120396 0.2794)
			(stroke
				(width 0.1)
				(type default)
			)
			(layer "F.Fab")
		)
		(fp_line
			(start 0.120396 0.2794)
			(end -0.12065 0.2794)
			(stroke
				(width 0.1)
				(type default)
			)
			(layer "F.Fab")
		)
		(fp_line
			(start -0.12065 0.3048)
			(end -0.67945 0.3048)
			(stroke
				(width 0.1)
				(type default)
			)
			(layer "F.Fab")
		)
		(fp_line
			(start -0.12065 0.2794)
			(end -0.12065 0.3048)
			(stroke
				(width 0.1)
				(type default)
			)
			(layer "F.Fab")
		)
		(fp_line
			(start -0.12065 -0.2794)
			(end 0.12065 -0.2794)
			(stroke
				(width 0.1)
				(type default)
			)
			(layer "F.Fab")
		)
		(fp_line
			(start -0.12065 -0.305054)
			(end -0.12065 -0.2794)
			(stroke
				(width 0.1)
				(type default)
			)
			(layer "F.Fab")
		)
		(fp_line
			(start -0.67945 0.3048)
			(end -0.67945 -0.305054)
			(stroke
				(width 0.1)
				(type default)
			)
			(layer "F.Fab")
		)
		(fp_line
			(start -0.67945 -0.305054)
			(end -0.12065 -0.305054)
			(stroke
				(width 0.1)
				(type default)
			)
			(layer "F.Fab")
		)
		(pad "1" smd circle
			(at -0.40005 0 180)
			(size 0 0)
			(layers "F.Cu" "F.Mask" "F.Paste")
			(net "SW_P12V_AUX_PVDDCR_CPU0_P1_FLT")
		)
		(pad "2" smd circle
			(at 0.40005 0 180)
			(size 0 0)
			(layers "F.Cu" "F.Mask" "F.Paste")
			(net "GND")
		)
	)
	(footprint ""
		(layer "F.Cu")
		(at 301.423324 -489.286042)
		(property "Reference" "ME9"
			(at 0 0 0)
			(layer "F.SilkS")
			(hide yes)
			(effects
				(font
					(size 1.27 1.27)
				)
			)
		)
		(property "Value" ""
			(at 0 0 0)
			(layer "F.Fab")
			(effects
				(font
					(size 1.27 1.27)
				)
			)
		)
		(duplicate_pad_numbers_are_jumpers no)
	)
	(footprint ""
		(layer "F.Cu")
		(at 210.439 -104.013 180)
		(property "Reference" "R8037"
			(at 0 0 180)
			(layer "F.SilkS")
			(hide yes)
			(effects
				(font
					(size 1.27 1.27)
				)
			)
		)
		(property "Value" ""
			(at 0 0 180)
			(layer "F.Fab")
			(effects
				(font
					(size 1.27 1.27)
				)
			)
		)
		(duplicate_pad_numbers_are_jumpers no)
		(fp_line
			(start 0.7874 0.4064)
			(end -0.7874 0.4064)
			(stroke
				(width 0.1524)
				(type default)
			)
			(layer "F.SilkS")
		)
		(fp_line
			(start 0.7874 -0.4064)
			(end 0.7874 0.4064)
			(stroke
				(width 0.1524)
				(type default)
			)
			(layer "F.SilkS")
		)
		(fp_line
			(start -0.7874 0.4064)
			(end -0.7874 -0.4064)
			(stroke
				(width 0.1524)
				(type default)
			)
			(layer "F.SilkS")
		)
		(fp_line
			(start -0.7874 -0.4064)
			(end 0.7874 -0.4064)
			(stroke
				(width 0.1524)
				(type default)
			)
			(layer "F.SilkS")
		)
		(fp_line
			(start 0.67945 0.3048)
			(end 0.120396 0.3048)
			(stroke
				(width 0.1)
				(type default)
			)
			(layer "F.Fab")
		)
		(fp_line
			(start 0.67945 -0.3048)
			(end 0.67945 0.3048)
			(stroke
				(width 0.1)
				(type default)
			)
			(layer "F.Fab")
		)
		(fp_line
			(start 0.12065 -0.2794)
			(end 0.12065 -0.3048)
			(stroke
				(width 0.1)
				(type default)
			)
			(layer "F.Fab")
		)
		(fp_line
			(start 0.12065 -0.3048)
			(end 0.67945 -0.3048)
			(stroke
				(width 0.1)
				(type default)
			)
			(layer "F.Fab")
		)
		(fp_line
			(start 0.120396 0.3048)
			(end 0.120396 0.2794)
			(stroke
				(width 0.1)
				(type default)
			)
			(layer "F.Fab")
		)
		(fp_line
			(start 0.120396 0.2794)
			(end -0.12065 0.2794)
			(stroke
				(width 0.1)
				(type default)
			)
			(layer "F.Fab")
		)
		(fp_line
			(start -0.12065 0.3048)
			(end -0.67945 0.3048)
			(stroke
				(width 0.1)
				(type default)
			)
			(layer "F.Fab")
		)
		(fp_line
			(start -0.12065 0.2794)
			(end -0.12065 0.3048)
			(stroke
				(width 0.1)
				(type default)
			)
			(layer "F.Fab")
		)
		(fp_line
			(start -0.12065 -0.2794)
			(end 0.12065 -0.2794)
			(stroke
				(width 0.1)
				(type default)
			)
			(layer "F.Fab")
		)
		(fp_line
			(start -0.12065 -0.305054)
			(end -0.12065 -0.2794)
			(stroke
				(width 0.1)
				(type default)
			)
			(layer "F.Fab")
		)
		(fp_line
			(start -0.67945 0.3048)
			(end -0.67945 -0.305054)
			(stroke
				(width 0.1)
				(type default)
			)
			(layer "F.Fab")
		)
		(fp_line
			(start -0.67945 -0.305054)
			(end -0.12065 -0.305054)
			(stroke
				(width 0.1)
				(type default)
			)
			(layer "F.Fab")
		)
		(pad "1" smd circle
			(at -0.40005 0 180)
			(size 0 0)
			(layers "F.Cu" "F.Mask" "F.Paste")
			(net "P3V3_AUX")
		)
		(pad "2" smd circle
			(at 0.40005 0 180)
			(size 0 0)
			(layers "F.Cu" "F.Mask" "F.Paste")
			(net "PWRGD_CHAF_CPU0")
		)
	)
	(footprint ""
		(layer "F.Cu")
		(at 421.65524 -378.95403 -90)
		(property "Reference" "C844"
			(at 0 0 270)
			(layer "F.SilkS")
			(hide yes)
			(effects
				(font
					(size 1.27 1.27)
				)
			)
		)
		(property "Value" ""
			(at 0 0 270)
			(layer "F.Fab")
			(effects
				(font
					(size 1.27 1.27)
				)
			)
		)
		(duplicate_pad_numbers_are_jumpers no)
		(fp_line
			(start -0.299974 0.150114)
			(end -0.299974 -0.150114)
			(stroke
				(width 0.1)
				(type default)
			)
			(layer "F.Fab")
		)
		(fp_line
			(start 0.299974 0.150114)
			(end -0.299974 0.150114)
			(stroke
				(width 0.1)
				(type default)
			)
			(layer "F.Fab")
		)
		(fp_line
			(start -0.299974 -0.150114)
			(end 0.299974 -0.150114)
			(stroke
				(width 0.1)
				(type default)
			)
			(layer "F.Fab")
		)
		(fp_line
			(start 0.299974 -0.150114)
			(end 0.299974 0.150114)
			(stroke
				(width 0.1)
				(type default)
			)
			(layer "F.Fab")
		)
		(pad "1" smd rect
			(at -0.2667 0 270)
			(size 0.3048 0.381)
			(layers "F.Cu" "F.Mask" "F.Paste")
			(net "P5E_CPU0_P2_TX_C_DN<12>")
		)
		(pad "2" smd rect
			(at 0.2667 0 270)
			(size 0.3048 0.381)
			(layers "F.Cu" "F.Mask" "F.Paste")
			(net "P5E_CPU0_P2_TX_DN<12>")
		)
	)
	(footprint ""
		(layer "F.Cu")
		(at 367.791492 -378.95403 -90)
		(property "Reference" "C895"
			(at 0 0 270)
			(layer "F.SilkS")
			(hide yes)
			(effects
				(font
					(size 1.27 1.27)
				)
			)
		)
		(property "Value" ""
			(at 0 0 270)
			(layer "F.Fab")
			(effects
				(font
					(size 1.27 1.27)
				)
			)
		)
		(duplicate_pad_numbers_are_jumpers no)
		(fp_line
			(start -0.299974 0.150114)
			(end -0.299974 -0.150114)
			(stroke
				(width 0.1)
				(type default)
			)
			(layer "F.Fab")
		)
		(fp_line
			(start 0.299974 0.150114)
			(end -0.299974 0.150114)
			(stroke
				(width 0.1)
				(type default)
			)
			(layer "F.Fab")
		)
		(fp_line
			(start -0.299974 -0.150114)
			(end 0.299974 -0.150114)
			(stroke
				(width 0.1)
				(type default)
			)
			(layer "F.Fab")
		)
		(fp_line
			(start 0.299974 -0.150114)
			(end 0.299974 0.150114)
			(stroke
				(width 0.1)
				(type default)
			)
			(layer "F.Fab")
		)
		(pad "1" smd rect
			(at -0.2667 0 270)
			(size 0.3048 0.381)
			(layers "F.Cu" "F.Mask" "F.Paste")
			(net "P5E_CPU0_P3_TX_C_DP<3>")
		)
		(pad "2" smd rect
			(at 0.2667 0 270)
			(size 0.3048 0.381)
			(layers "F.Cu" "F.Mask" "F.Paste")
			(net "P5E_CPU0_P3_TX_DP<3>")
		)
	)
)
